# T6G (Grand Teton) — schematic parts with pin connectivity, parts 2649–2649 of 8303; source: Cadence DE-HDL packaged netlist (pstxprt.dat, pstxnet.dat, pstchip.dat)

J100  SCONN288_DDR506112002KQ  IO  pkg DDR288S_1-1VXC  page 106
  1  VIN_BULK0  POWER  = P12V_MEM_CPU1
  2  RFU0  TRI  = NC
  3  VIN_MGMT  POWER  = P3V3_AUX
  4  HSCL  IN  = I3C_SPD_DDRI_CPU1_SCL
  5  HSDA  BI  = I3C_SPD_DDRI_CPU1_SDA
  6  VSS0  POWER  = GND
  7  DQ0_A  BI  = M_I_CPU1_SA_DQ<0>
  8  VSS1  POWER  = GND
  9  DQ1_A  BI  = M_I_CPU1_SA_DQ<1>
  10  VSS2  POWER  = GND
  11  DQS0_A_T  BI  = M_I_CPU1_SA_DQS_DP<0>
  12  DQS0_A_C  BI  = M_I_CPU1_SA_DQS_DN<0>
  13  VSS3  POWER  = GND
  14  DQ4_A  BI  = M_I_CPU1_SA_DQ<4>
  15  VSS4  POWER  = GND
  16  DQ5_A  BI  = M_I_CPU1_SA_DQ<5>
  17  VSS5  POWER  = GND
  18  DQ8_A  BI  = M_I_CPU1_SA_DQ<8>
  19  VSS6  POWER  = GND
  20  DQ9_A  BI  = M_I_CPU1_SA_DQ<9>
  21  VSS7  POWER  = GND
  22  DQS1_A_T  BI  = M_I_CPU1_SA_DQS_DP<1>
  23  DQS1_A_C  BI  = M_I_CPU1_SA_DQS_DN<1>
  24  VSS8  POWER  = GND
  25  DQ12_A  BI  = M_I_CPU1_SA_DQ<12>
  26  VSS9  POWER  = GND
  27  DQ13_A  BI  = M_I_CPU1_SA_DQ<13>
  28  VSS10  POWER  = GND
  29  DQ16_A  BI  = M_I_CPU1_SA_DQ<16>
  30  VSS11  POWER  = GND
  31  DQ17_A  BI  = M_I_CPU1_SA_DQ<17>
  32  VSS12  POWER  = GND
  33  DQS2_A_T  BI  = M_I_CPU1_SA_DQS_DP<2>
  34  DQS2_A_C  BI  = M_I_CPU1_SA_DQS_DN<2>
  35  VSS13  POWER  = GND
  36  DQ20_A  BI  = M_I_CPU1_SA_DQ<20>
  37  VSS14  POWER  = GND
  38  DQ21_A  BI  = M_I_CPU1_SA_DQ<21>
  39  VSS15  POWER  = GND
  40  DQ24_A  BI  = M_I_CPU1_SA_DQ<24>
  41  VSS16  POWER  = GND
  42  DQ25_A  BI  = M_I_CPU1_SA_DQ<25>
  43  VSS17  POWER  = GND
  44  DQS3_A_T  BI  = M_I_CPU1_SA_DQS_DP<3>
  45  DQS3_A_C  BI  = M_I_CPU1_SA_DQS_DN<3>
  46  VSS18  POWER  = GND
  47  DQ28_A  BI  = M_I_CPU1_SA_DQ<28>
  48  VSS19  POWER  = GND
  49  DQ29_A  BI  = M_I_CPU1_SA_DQ<29>
  50  VSS20  POWER  = GND
  51  CB0_A  BI  = M_I_CPU1_SA_CB<0>
  52  VSS21  POWER  = GND
  53  CB1_A  BI  = M_I_CPU1_SA_CB<1>
  54  VSS22  POWER  = GND
  55  DQS4_A_T  BI  = M_I_CPU1_SA_DQS_DP<4>
  56  DQS4_A_C  BI  = M_I_CPU1_SA_DQS_DN<4>
  57  VSS23  POWER  = GND
  58  CB4_A  BI  = M_I_CPU1_SA_CB<4>
  59  VSS24  POWER  = GND
  60  CB5_A  BI  = M_I_CPU1_SA_CB<5>
  61  VSS25  POWER  = GND
  62  ALERT_N  OUT  = M_I_CPU1_ALERT_N
  63  VSS26  POWER  = GND
  64  CS0_A_N  IN  = M_I_CPU1_SA_CS_N<0>
  65  VSS27  POWER  = GND
  66  CA0_A  IN  = M_I_CPU1_SA_CA<0>
  67  VSS28  POWER  = GND
  68  CA2_A  IN  = M_I_CPU1_SA_CA<2>
  69  VSS29  POWER  = GND
  70  CA4_A  IN  = M_I_CPU1_SA_CA<4>
  71  VSS30  POWER  = GND
  72  CA6_A  IN  = M_I_CPU1_SA_CA<6>
  73  VSS31  POWER  = GND
  74  PAR_A  IN  = M_I_CPU1_SA_PAR
  75  VSS32  POWER  = GND
  76  CA0_B  IN  = M_I_CPU1_SB_CA<0>
  77  VSS33  POWER  = GND
  78  CA2_B  IN  = M_I_CPU1_SB_CA<2>
  79  VSS34  POWER  = GND
  80  CA4_B  IN  = M_I_CPU1_SB_CA<4>
  81  VSS35  POWER  = GND
  82  CA6_B  IN  = M_I_CPU1_SB_CA<6>
  83  VSS36  POWER  = GND
  84  CS0_B_N  IN  = M_I_CPU1_SB_CS_N<0>
  85  VSS37  POWER  = GND
  86  \lbd||rsp_a_n\  OUT  = M_I_CPU1_SA_RSP<0>
  87  \lbs||rsp_b_n\  OUT  = M_I_CPU1_SB_RSP<0>
  88  VSS38  POWER  = GND
  89  CB4_B  BI  = M_I_CPU1_SB_CB<4>
  90  VSS39  POWER  = GND
  91  CB5_B  BI  = M_I_CPU1_SB_CB<5>
  92  VSS40  POWER  = GND
  93  \dqs9_b_t||tdqs9_b_t||dbi4_b_n\  BI  = M_I_CPU1_SB_DQS_DP<9>
  94  \dqs9_b_c||tdqs9_b_c\  BI  = M_I_CPU1_SB_DQS_DN<9>
  95  VSS41  POWER  = GND
  96  CB0_B  BI  = M_I_CPU1_SB_CB<0>
  97  VSS42  POWER  = GND
  98  CB1_B  BI  = M_I_CPU1_SB_CB<1>
  99  VSS43  POWER  = GND
  100  DQ0_B  BI  = M_I_CPU1_SB_DQ<0>
  101  VSS44  POWER  = GND
  102  DQ1_B  BI  = M_I_CPU1_SB_DQ<1>
  103  VSS45  POWER  = GND
  104  DQS0_B_T  BI  = M_I_CPU1_SB_DQS_DP<0>
  105  DQS0_B_C  BI  = M_I_CPU1_SB_DQS_DN<0>
  106  VSS46  POWER  = GND
  107  DQ4_B  BI  = M_I_CPU1_SB_DQ<4>
  108  VSS47  POWER  = GND
  109  DQ5_B  BI  = M_I_CPU1_SB_DQ<5>
  110  VSS48  POWER  = GND
  111  DQ8_B  BI  = M_I_CPU1_SB_DQ<8>
  112  VSS49  POWER  = GND
  113  DQ9_B  BI  = M_I_CPU1_SB_DQ<9>
  114  VSS50  POWER  = GND
  115  DQS1_B_T  BI  = M_I_CPU1_SB_DQS_DP<1>
  116  DQS1_B_C  BI  = M_I_CPU1_SB_DQS_DN<1>
  117  VSS51  POWER  = GND
  118  DQ12_B  BI  = M_I_CPU1_SB_DQ<12>
  119  VSS52  POWER  = GND
  120  DQ13_B  BI  = M_I_CPU1_SB_DQ<13>
  121  VSS53  POWER  = GND
  122  DQ16_B  BI  = M_I_CPU1_SB_DQ<16>
  123  VSS54  POWER  = GND
  124  DQ17_B  BI  = M_I_CPU1_SB_DQ<17>
  125  VSS55  POWER  = GND
  126  DQS2_B_T  BI  = M_I_CPU1_SB_DQS_DP<2>
  127  DQS2_B_C  BI  = M_I_CPU1_SB_DQS_DN<2>
  128  VSS56  POWER  = GND
  129  DQ20_B  BI  = M_I_CPU1_SB_DQ<20>
  130  VSS57  POWER  = GND
  131  DQ21_B  BI  = M_I_CPU1_SB_DQ<21>
  132  VSS58  POWER  = GND
  133  DQ24_B  BI  = M_I_CPU1_SB_DQ<24>
  134  VSS59  POWER  = GND
  135  DQ25_B  BI  = M_I_CPU1_SB_DQ<25>
  136  VSS60  POWER  = GND
  137  DQS3_B_T  BI  = M_I_CPU1_SB_DQS_DP<3>
  138  DQS3_B_C  BI  = M_I_CPU1_SB_DQS_DN<3>
  139  VSS61  POWER  = GND
  140  DQ28_B  BI  = M_I_CPU1_SB_DQ<28>
  141  VSS62  POWER  = GND
  142  DQ29_B  BI  = M_I_CPU1_SB_DQ<29>
  143  VSS63  POWER  = GND
  144  RFU1  TRI  = NC
  145  VIN_BULK1  POWER  = P12V_MEM_CPU1
  146  VIN_BULK2  POWER  = P12V_MEM_CPU1
  147  \pwr_good||fail_n\  BI  = PWRGD_CHI_CPU1_DIMM
  148  HAS  IN  = PD_CHI_CPU1_DIMM_SAA
  149  RFU2  TRI  = NC
  150  RFU3  TRI  = NC
  151  VSS64  POWER  = GND
  152  DQ2_A  BI  = M_I_CPU1_SA_DQ<2>
  153  VSS65  POWER  = GND
  154  DQ3_A  BI  = M_I_CPU1_SA_DQ<3>
  155  VSS66  POWER  = GND
  156  \dqs5_a_c||tdqs5_a_c||dqs5_a_t||tdqs5_a_t\  BI  = M_I_CPU1_SA_DQS_DN<5>
  157  \dqs5_a_t||tdqs5_a_t\  BI  = M_I_CPU1_SA_DQS_DP<5>
  158  VSS67  POWER  = GND
  159  DQ6_A  BI  = M_I_CPU1_SA_DQ<6>
  160  VSS68  POWER  = GND
  161  DQ7_A  BI  = M_I_CPU1_SA_DQ<7>
  162  VSS69  POWER  = GND
  163  DQ10_A  BI  = M_I_CPU1_SA_DQ<10>
  164  VSS70  POWER  = GND
  165  DQ11_A  BI  = M_I_CPU1_SA_DQ<11>
  166  VSS71  POWER  = GND
  167  \dqs6_a_c||tdqs6_a_c||dqs6_a_t||tdqs6_a_t\  BI  = M_I_CPU1_SA_DQS_DN<6>
  168  \dqs6_a_t||tdqs6_a_t\  BI  = M_I_CPU1_SA_DQS_DP<6>
  169  VSS72  POWER  = GND
  170  DQ14_A  BI  = M_I_CPU1_SA_DQ<14>
  171  VSS73  POWER  = GND
  172  DQ15_A  BI  = M_I_CPU1_SA_DQ<15>
  173  VSS74  POWER  = GND
  174  DQ18_A  BI  = M_I_CPU1_SA_DQ<18>
  175  VSS75  POWER  = GND
  176  DQ19_A  BI  = M_I_CPU1_SA_DQ<19>
  177  VSS76  POWER  = GND
  178  \dqs7_a_c||tdqs7_a_c\  BI  = M_I_CPU1_SA_DQS_DN<7>
  179  \dqs7_a_t||tdqs7_a_t\  BI  = M_I_CPU1_SA_DQS_DP<7>
  180  VSS77  POWER  = GND
  181  DQ22_A  BI  = M_I_CPU1_SA_DQ<22>
  182  VSS78  POWER  = GND
  183  DQ23_A  BI  = M_I_CPU1_SA_DQ<23>
  184  VSS79  POWER  = GND
  185  DQ26_A  BI  = M_I_CPU1_SA_DQ<26>
  186  VSS80  POWER  = GND
  187  DQ27_A  BI  = M_I_CPU1_SA_DQ<27>
  188  VSS81  POWER  = GND
  189  \dqs8_a_c||tdqs8_a_c\  BI  = M_I_CPU1_SA_DQS_DN<8>
  190  \dqs8_a_t||tdqs8_a_t\  BI  = M_I_CPU1_SA_DQS_DP<8>
  191  VSS82  POWER  = GND
  192  DQ30_A  BI  = M_I_CPU1_SA_DQ<30>
  193  VSS83  POWER  = GND
  194  DQ31_A  BI  = M_I_CPU1_SA_DQ<31>
  195  VSS84  POWER  = GND
  196  CB2_A  BI  = M_I_CPU1_SA_CB<2>
  197  VSS85  POWER  = GND
  198  CB3_A  BI  = M_I_CPU1_SA_CB<3>
  199  VSS86  POWER  = GND
  200  \dqs9_a_c||tdqs9_a_c\  BI  = M_I_CPU1_SA_DQS_DN<9>
  201  \dqs9_a_t||tdqs9_a_t\  BI  = M_I_CPU1_SA_DQS_DP<9>
  202  VSS87  POWER  = GND
  203  CB6_A  BI  = M_I_CPU1_SA_CB<6>
  204  VSS88  POWER  = GND
  205  CB7_A  BI  = M_I_CPU1_SA_CB<7>
  206  VSS89  POWER  = GND
  207  RESET_N  IN  = M_I_CPU1_RESET_N
  208  VSS90  POWER  = GND
  209  CS1_A_N  IN  = M_I_CPU1_SA_CS_N<1>
  210  VSS91  POWER  = GND
  211  CA1_A  IN  = M_I_CPU1_SA_CA<1>
  212  VSS92  POWER  = GND
  213  CA3_A  IN  = M_I_CPU1_SA_CA<3>
  214  VSS93  POWER  = GND
  215  CA5_A  IN  = M_I_CPU1_SA_CA<5>
  216  VSS94  POWER  = GND
  217  CK_T  IN  = M_I_CPU1_CLK_DP<0>
  218  CK_C  IN  = M_I_CPU1_CLK_DN<0>
  219  VSS95  POWER  = GND
  220  RFU4  TRI  = NC
  221  CA1_B  IN  = M_I_CPU1_SB_CA<1>
  222  VSS96  POWER  = GND
  223  CA3_B  IN  = M_I_CPU1_SB_CA<3>
  224  VSS97  POWER  = GND
  225  CA5_B  IN  = M_I_CPU1_SB_CA<5>
  226  VSS98  POWER  = GND
  227  PAR_B  IN  = M_I_CPU1_SB_PAR
  228  VSS99  POWER  = GND
  229  CS1_B_N  IN  = M_I_CPU1_SB_CS_N<1>
  230  VSS100  POWER  = GND
  231  RFU5  TRI  = NC
  232  RFU6  TRI  = NC
  233  VSS101  POWER  = GND
  234  CB6_B  BI  = M_I_CPU1_SB_CB<6>
  235  VSS102  POWER  = GND
  236  CB7_B  BI  = M_I_CPU1_SB_CB<7>
  237  VSS103  POWER  = GND
  238  DQS4_B_C  BI  = M_I_CPU1_SB_DQS_DN<4>
  239  DQS4_B_T  BI  = M_I_CPU1_SB_DQS_DP<4>
  240  VSS104  POWER  = GND
  241  CB2_B  BI  = M_I_CPU1_SB_CB<2>
  242  VSS105  POWER  = GND
  243  CB3_B  BI  = M_I_CPU1_SB_CB<3>
  244  VSS106  POWER  = GND
  245  DQ2_B  BI  = M_I_CPU1_SB_DQ<2>
  246  VSS107  POWER  = GND
  247  DQ3_B  BI  = M_I_CPU1_SB_DQ<3>
  248  VSS108  POWER  = GND
  249  \dqs5_b_c||tdqs5_b_c\  BI  = M_I_CPU1_SB_DQS_DN<5>
  250  \dqs5_b_t||tdqs5_b_t\  BI  = M_I_CPU1_SB_DQS_DP<5>
  251  VSS109  POWER  = GND
  252  DQ6_B  BI  = M_I_CPU1_SB_DQ<6>
  253  VSS110  POWER  = GND
  254  DQ7_B  BI  = M_I_CPU1_SB_DQ<7>
  255  VSS111  POWER  = GND
  256  DQ10_B  BI  = M_I_CPU1_SB_DQ<10>
  257  VSS112  POWER  = GND
  258  DQ11_B  BI  = M_I_CPU1_SB_DQ<11>
  259  VSS113  POWER  = GND
  260  \dqs6_b_c||tdqs6_b_c\  BI  = M_I_CPU1_SB_DQS_DN<6>
  261  \dqs6_b_t||tdqs6_b_t\  BI  = M_I_CPU1_SB_DQS_DP<6>
  262  VSS114  POWER  = GND
  263  DQ14_B  BI  = M_I_CPU1_SB_DQ<14>
  264  VSS115  POWER  = GND
  265  DQ15_B  BI  = M_I_CPU1_SB_DQ<15>
  266  VSS116  POWER  = GND
  267  DQ18_B  BI  = M_I_CPU1_SB_DQ<18>
  268  VSS117  POWER  = GND
  269  DQ19_B  BI  = M_I_CPU1_SB_DQ<19>
  270  VSS118  POWER  = GND
  271  \dqs7_b_c||tdqs7_b_c\  BI  = M_I_CPU1_SB_DQS_DN<7>
  272  \dqs7_b_t||tdqs7_b_t\  BI  = M_I_CPU1_SB_DQS_DP<7>
  273  VSS119  POWER  = GND
  274  DQ22_B  BI  = M_I_CPU1_SB_DQ<22>
  275  VSS120  POWER  = GND
  276  DQ23_B  BI  = M_I_CPU1_SB_DQ<23>
  277  VSS121  POWER  = GND
  278  DQ26_B  BI  = M_I_CPU1_SB_DQ<26>
  279  VSS122  POWER  = GND
  280  DQ27_B  BI  = M_I_CPU1_SB_DQ<27>
  281  VSS123  POWER  = GND
  282  \dqs8_b_c||tdqs8_b_c\  BI  = M_I_CPU1_SB_DQS_DN<8>
  283  \dqs8_b_t||tdqs8_b_t\  BI  = M_I_CPU1_SB_DQS_DP<8>
  284  VSS124  POWER  = GND
  285  DQ30_B  BI  = M_I_CPU1_SB_DQ<30>
  286  VSS125  POWER  = GND
  287  DQ31_B  BI  = M_I_CPU1_SB_DQ<31>
  288  VSS126  POWER  = GND
  G1  G1  POWER  = GND
  G2  G2  POWER  = GND
  G3  G3  POWER  = GND
